# S9S_MB_2U (Grand Teton) — schematic netlist excerpt (pin names and nets, part order shuffled) for the footprints in the layout excerpt that follows; sources: Cadence DE-HDL packaged netlist, KiCad conversion of 03242023_DA0F0TMBIJ0_F0T_Motherboard_J_brd_V01_OCP.brd

C1796  Q_CAP  0.1UF 25V 10% X7R  pkg 0402  page 234 : A = P3V3_AUX ; B = GND

Q138  BC847BPN  IC  pkg SOT363XB  page 121
  E1  = GND
  B1  = H_CPU0_THERMTRIP_R_N
  C2  = H_CPU0_THERMTRIP_N
  E2  = PVNN_TERM_CPU0
  B2  = H_CPU0_THERMTRIP_VT_R_N
  C1  = H_CPU0_THERMTRIP_VT_N

(kicad_pcb
	(version 20260206)
	(generator "pcbnew")
	(generator_version "10.0")
	(general
		(thickness 1.6)
		(legacy_teardrops no)
	)
	(paper "A4")
	(title_block
		(title "03242023_DA0F0TMBIJ0_F0T_Motherboard_J_brd_V01_OCP.brd")
		(comment 1 "Grand Teton / footprints 2135-2136 of 6105")
	)
	(layers
		(0 "F.Cu" signal "TOP")
		(4 "In1.Cu" signal "GND")
		(6 "In2.Cu" signal "IN1")
		(8 "In3.Cu" signal "GND1")
		(10 "In4.Cu" signal "IN2")
		(12 "In5.Cu" signal "GND2")
		(14 "In6.Cu" signal "IN3")
		(16 "In7.Cu" signal "GND3")
		(18 "In8.Cu" signal "VCC")
		(20 "In9.Cu" signal "VCC1")
		(22 "In10.Cu" signal "GND4")
		(24 "In11.Cu" signal "IN4")
		(26 "In12.Cu" signal "GND5")
		(28 "In13.Cu" signal "IN5")
		(30 "In14.Cu" signal "GND6")
		(32 "In15.Cu" signal "IN6")
		(34 "In16.Cu" signal "GND7")
		(2 "B.Cu" signal "BOTTOM")
		(9 "F.Adhes" user "F.Adhesive")
		(11 "B.Adhes" user "B.Adhesive")
		(13 "F.Paste" user "Package Geometry/Pastemask Top")
		(15 "B.Paste" user "Package Geometry/Pastemask Bottom")
		(5 "F.SilkS" user "Ref Des/Silkscreen Top")
		(7 "B.SilkS" user "Ref Des/Silkscreen Bottom")
		(1 "F.Mask" user "Board Geometry/Soldermask Top")
		(3 "B.Mask" user "Board Geometry/Soldermask Bottom")
		(17 "Dwgs.User" user "User.Drawings")
		(19 "Cmts.User" user "User.Comments")
		(21 "Eco1.User" user "User.Eco1")
		(23 "Eco2.User" user "User.Eco2")
		(25 "Edge.Cuts" user "Board Geometry/Outline")
		(27 "Margin" user)
		(31 "F.CrtYd" user "Package Geometry/Place Bound Top")
		(29 "B.CrtYd" user "Package Geometry/Place Bound Bottom")
		(35 "F.Fab" user "Ref Des/Assembly Top")
		(33 "B.Fab" user "Ref Des/Assembly Bottom")
	)
	(footprint ""
		(layer "F.Cu")
		(at 122.61088 -96.230948 -90)
		(property "Reference" "Q138"
			(at -4.130802 0.18288 0)
			(unlocked yes)
			(layer "F.SilkS")
			(effects
				(font
					(size 0.635 0.4064)
					(thickness 0.1524)
				)
			)
		)
		(property "Value" ""
			(at 0 0 270)
			(layer "F.Fab")
			(effects
				(font
					(size 1.27 1.27)
				)
			)
		)
		(duplicate_pad_numbers_are_jumpers no)
		(fp_line
			(start -1.376172 1.199896)
			(end -1.376172 -1.199896)
			(stroke
				(width 0.1524)
				(type default)
			)
			(layer "F.SilkS")
		)
		(fp_line
			(start 1.376172 1.199896)
			(end -1.376172 1.199896)
			(stroke
				(width 0.1524)
				(type default)
			)
			(layer "F.SilkS")
		)
		(fp_line
			(start 0 -0.762)
			(end 0.508 -1.199896)
			(stroke
				(width 0.1524)
				(type default)
			)
			(layer "F.SilkS")
		)
		(fp_line
			(start -1.376172 -1.199896)
			(end -0.508 -1.199896)
			(stroke
				(width 0.1524)
				(type default)
			)
			(layer "F.SilkS")
		)
		(fp_line
			(start -0.508 -1.199896)
			(end 0 -0.762)
			(stroke
				(width 0.1524)
				(type default)
			)
			(layer "F.SilkS")
		)
		(fp_line
			(start 0.508 -1.199896)
			(end 1.376172 -1.199896)
			(stroke
				(width 0.1524)
				(type default)
			)
			(layer "F.SilkS")
		)
		(fp_line
			(start 1.376172 -1.199896)
			(end 1.376172 1.199896)
			(stroke
				(width 0.1524)
				(type default)
			)
			(layer "F.SilkS")
		)
		(fp_poly
			(pts
				(xy -1.5875 -1.0033) (xy -2.3495 -1.3843) (xy -2.3495 -0.6223)
			)
			(stroke
				(width 0)
				(type default)
			)
			(fill yes)
			(layer "F.SilkS")
		)
		(fp_line
			(start -0.674878 1.100074)
			(end -0.674878 -1.100074)
			(stroke
				(width 0.1)
				(type default)
			)
			(layer "F.Fab")
		)
		(fp_line
			(start 0.674878 1.100074)
			(end -0.674878 1.100074)
			(stroke
				(width 0.1)
				(type default)
			)
			(layer "F.Fab")
		)
		(fp_line
			(start -0.674878 -1.100074)
			(end 0.674878 -1.100074)
			(stroke
				(width 0.1)
				(type default)
			)
			(layer "F.Fab")
		)
		(fp_line
			(start 0.674878 -1.100074)
			(end 0.674878 1.100074)
			(stroke
				(width 0.1)
				(type default)
			)
			(layer "F.Fab")
		)
		(fp_poly
			(pts
				(xy -1.4605 -0.7493) (xy -2.2225 -1.1303) (xy -2.2225 -0.3683)
			)
			(stroke
				(width 0)
				(type default)
			)
			(fill yes)
			(layer "F.Fab")
		)
		(pad "1" smd rect
			(at -0.899922 -0.750062 180)
			(size 0.6096 0.6096)
			(layers "F.Cu" "F.Mask" "F.Paste")
			(net "GND")
		)
		(pad "2" smd rect
			(at -0.899922 0 180)
			(size 0.4064 0.6096)
			(layers "F.Cu" "F.Mask" "F.Paste")
			(net "H_CPU0_THERMTRIP_R_N")
		)
		(pad "3" smd rect
			(at -0.899922 0.750062 180)
			(size 0.6096 0.6096)
			(layers "F.Cu" "F.Mask" "F.Paste")
			(net "H_CPU0_THERMTRIP_N")
		)
		(pad "4" smd rect
			(at 0.899922 0.750062 180)
			(size 0.6096 0.6096)
			(layers "F.Cu" "F.Mask" "F.Paste")
			(net "PVNN_TERM_CPU0")
		)
		(pad "5" smd rect
			(at 0.899922 0 180)
			(size 0.4064 0.6096)
			(layers "F.Cu" "F.Mask" "F.Paste")
			(net "H_CPU0_THERMTRIP_VT_R_N")
		)
		(pad "6" smd rect
			(at 0.899922 -0.750062 180)
			(size 0.6096 0.6096)
			(layers "F.Cu" "F.Mask" "F.Paste")
			(net "H_CPU0_THERMTRIP_VT_N")
		)
	)
	(footprint ""
		(layer "F.Cu")
		(at 35.577018 -436.903368 180)
		(property "Reference" "C1796"
			(at 0 0 180)
			(layer "F.SilkS")
			(hide yes)
			(effects
				(font
					(size 1.27 1.27)
				)
			)
		)
		(property "Value" ""
			(at 0 0 180)
			(layer "F.Fab")
			(effects
				(font
					(size 1.27 1.27)
				)
			)
		)
		(duplicate_pad_numbers_are_jumpers no)
		(fp_line
			(start 0.7874 0.4064)
			(end -0.7874 0.4064)
			(stroke
				(width 0.1524)
				(type default)
			)
			(layer "F.SilkS")
		)
		(fp_line
			(start 0.7874 -0.4064)
			(end 0.7874 0.4064)
			(stroke
				(width 0.1524)
				(type default)
			)
			(layer "F.SilkS")
		)
		(fp_line
			(start -0.7874 0.4064)
			(end -0.7874 -0.4064)
			(stroke
				(width 0.1524)
				(type default)
			)
			(layer "F.SilkS")
		)
		(fp_line
			(start -0.7874 -0.4064)
			(end 0.7874 -0.4064)
			(stroke
				(width 0.1524)
				(type default)
			)
			(layer "F.SilkS")
		)
		(fp_line
			(start 0.67945 0.3048)
			(end 0.120396 0.3048)
			(stroke
				(width 0.1)
				(type default)
			)
			(layer "F.Fab")
		)
		(fp_line
			(start 0.67945 -0.3048)
			(end 0.67945 0.3048)
			(stroke
				(width 0.1)
				(type default)
			)
			(layer "F.Fab")
		)
		(fp_line
			(start 0.12065 -0.2794)
			(end 0.12065 -0.3048)
			(stroke
				(width 0.1)
				(type default)
			)
			(layer "F.Fab")
		)
		(fp_line
			(start 0.12065 -0.3048)
			(end 0.67945 -0.3048)
			(stroke
				(width 0.1)
				(type default)
			)
			(layer "F.Fab")
		)
		(fp_line
			(start 0.120396 0.3048)
			(end 0.120396 0.2794)
			(stroke
				(width 0.1)
				(type default)
			)
			(layer "F.Fab")
		)
		(fp_line
			(start 0.120396 0.2794)
			(end -0.12065 0.2794)
			(stroke
				(width 0.1)
				(type default)
			)
			(layer "F.Fab")
		)
		(fp_line
			(start -0.12065 0.3048)
			(end -0.67945 0.3048)
			(stroke
				(width 0.1)
				(type default)
			)
			(layer "F.Fab")
		)
		(fp_line
			(start -0.12065 0.2794)
			(end -0.12065 0.3048)
			(stroke
				(width 0.1)
				(type default)
			)
			(layer "F.Fab")
		)
		(fp_line
			(start -0.12065 -0.2794)
			(end 0.12065 -0.2794)
			(stroke
				(width 0.1)
				(type default)
			)
			(layer "F.Fab")
		)
		(fp_line
			(start -0.12065 -0.305054)
			(end -0.12065 -0.2794)
			(stroke
				(width 0.1)
				(type default)
			)
			(layer "F.Fab")
		)
		(fp_line
			(start -0.67945 0.3048)
			(end -0.67945 -0.305054)
			(stroke
				(width 0.1)
				(type default)
			)
			(layer "F.Fab")
		)
		(fp_line
			(start -0.67945 -0.305054)
			(end -0.12065 -0.305054)
			(stroke
				(width 0.1)
				(type default)
			)
			(layer "F.Fab")
		)
		(pad "1" smd circle
			(at -0.40005 0 180)
			(size 0 0)
			(layers "F.Cu" "F.Mask" "F.Paste")
			(net "P3V3_AUX")
		)
		(pad "2" smd circle
			(at 0.40005 0 180)
			(size 0 0)
			(layers "F.Cu" "F.Mask" "F.Paste")
			(net "GND")
		)
	)
)
